(kicad_pcb
	(version 20260206)
	(generator "pcbnew")
	(generator_version "10.0")
	(general
		(thickness 1.6)
		(legacy_teardrops no)
	)
	(paper "A4")
	(title_block
		(title "timecard-production-celestica-r4006 — R4006-B0001-02_R01.brd")
		(comment 1 "Time Appliance Project (Time Card) / footprints 495-498 of 1113")
	)
	(layers
		(0 "F.Cu" signal "TOP")
		(4 "In1.Cu" signal "L02_GND1")
		(6 "In2.Cu" signal "L03_SIG1")
		(8 "In3.Cu" signal "L04_GND2")
		(10 "In4.Cu" signal "L05_VCC1")
		(12 "In5.Cu" signal "L06_VCC2")
		(14 "In6.Cu" signal "L07_GND3")
		(16 "In7.Cu" signal "L08_SIG2")
		(18 "In8.Cu" signal "L09_GND4")
		(2 "B.Cu" signal "BOTTOM")
		(9 "F.Adhes" user "F.Adhesive")
		(11 "B.Adhes" user "B.Adhesive")
		(13 "F.Paste" user "Package Geometry/Pastemask Top")
		(15 "B.Paste" user "Package Geometry/Pastemask Bottom")
		(5 "F.SilkS" user "Ref Des/Silkscreen Top")
		(7 "B.SilkS" user "Ref Des/Silkscreen Bottom")
		(1 "F.Mask" user "Board Geometry/Soldermask Top")
		(3 "B.Mask" user "Board Geometry/Soldermask Bottom")
		(17 "Dwgs.User" user "User.Drawings")
		(19 "Cmts.User" user "User.Comments")
		(21 "Eco1.User" user "User.Eco1")
		(23 "Eco2.User" user "User.Eco2")
		(25 "Edge.Cuts" user "Board Geometry/Outline")
		(27 "Margin" user)
		(31 "F.CrtYd" user "Package Geometry/Place Bound Top")
		(29 "B.CrtYd" user "Package Geometry/Place Bound Bottom")
		(35 "F.Fab" user "Ref Des/Assembly Top")
		(33 "B.Fab" user "Ref Des/Assembly Bottom")
	)
	(footprint ""
		(layer "F.Cu")
		(at 80.772 -62.9666 180)
		(property "Reference" "R307"
			(at 10.287 19.41703 0)
			(unlocked yes)
			(layer "F.SilkS")
			(effects
				(font
					(size 0.7874 0.5842)
					(thickness 0.1524)
				)
			)
		)
		(property "Value" "VAL*"
			(at 0.02032 2.13233 180)
			(unlocked yes)
			(layer "F.Fab")
			(hide yes)
			(effects
				(font
					(size 0.7874 0.5842)
					(thickness 0.1524)
				)
			)
		)
		(property "Device Type" "RESISTOR-G155-11001-01,1KOHM,1%"
			(at 0.008382 1.210564 180)
			(unlocked yes)
			(layer "F.Fab")
			(hide yes)
			(effects
				(font
					(size 0.7874 0.5842)
					(thickness 0.1524)
				)
			)
		)
		(property "User Part Number" "PARTNUM*"
			(at 0.02032 4.024884 180)
			(unlocked yes)
			(layer "Cmts.User")
			(hide yes)
			(effects
				(font
					(size 0.7874 0.5842)
					(thickness 0.1524)
				)
			)
		)
		(property "Tolerance" "TOL*"
			(at 0.044704 3.05435 180)
			(unlocked yes)
			(layer "Cmts.User")
			(hide yes)
			(effects
				(font
					(size 0.7874 0.5842)
					(thickness 0.1524)
				)
			)
		)
		(duplicate_pad_numbers_are_jumpers no)
		(fp_line
			(start 1.143 0.5588)
			(end 1.143 -0.5588)
			(stroke
				(width 0.1)
				(type default)
			)
			(layer "F.SilkS")
		)
		(fp_line
			(start 1.143 -0.5588)
			(end -1.143 -0.5588)
			(stroke
				(width 0.1)
				(type default)
			)
			(layer "F.SilkS")
		)
		(fp_line
			(start -1.143 0.5588)
			(end 1.143 0.5588)
			(stroke
				(width 0.1)
				(type default)
			)
			(layer "F.SilkS")
		)
		(fp_line
			(start -1.143 -0.5588)
			(end -1.143 0.5588)
			(stroke
				(width 0.1)
				(type default)
			)
			(layer "F.SilkS")
		)
		(fp_rect
			(start 1.143 -0.5588)
			(end -1.143 0.5588)
			(stroke
				(width 0)
				(type default)
			)
			(fill no)
			(layer "F.CrtYd")
		)
		(fp_line
			(start 0.508 0.3048)
			(end 0.508 -0.3048)
			(stroke
				(width 0.1)
				(type default)
			)
			(layer "F.Fab")
		)
		(fp_line
			(start 0.508 -0.3048)
			(end -0.508 -0.3048)
			(stroke
				(width 0.1)
				(type default)
			)
			(layer "F.Fab")
		)
		(fp_line
			(start -0.508 0.3048)
			(end 0.508 0.3048)
			(stroke
				(width 0.1)
				(type default)
			)
			(layer "F.Fab")
		)
		(fp_line
			(start -0.508 -0.3048)
			(end -0.508 0.3048)
			(stroke
				(width 0.1)
				(type default)
			)
			(layer "F.Fab")
		)
		(pad "1" smd rect
			(at -0.5334 0 180)
			(size 0.7112 0.6096)
			(layers "F.Cu" "F.Mask" "F.Paste")
			(net "UNNAMED_9_BNO080LGA28_I29_CLKSE")
		)
		(pad "2" smd rect
			(at 0.5334 0 180)
			(size 0.7112 0.6096)
			(layers "F.Cu" "F.Mask" "F.Paste")
			(net "SG")
		)
		(zone
			(layer "F.Cu")
			(hatch none 0.5)
			(connect_pads
				(clearance 0)
			)
			(min_thickness 0.25)
			(keepout
				(tracks allowed)
				(vias not_allowed)
				(pads allowed)
				(copperpour not_allowed)
				(footprints allowed)
			)
			(placement
				(enabled no)
				(sheetname "")
			)
			(fill
				(thermal_gap 0.5)
				(thermal_bridge_width 0.5)
				(island_removal_mode 0)
			)
			(polygon
				(pts
					(xy 80.6958 -62.6618) (xy 80.8482 -62.6618) (xy 80.8482 -63.2714) (xy 80.6958 -63.2714)
				)
			)
		)
	)
	(footprint ""
		(layer "F.Cu")
		(at 92.837 -56.007 180)
		(property "Reference" "L33"
			(at 1.0795 -1.30937 0)
			(unlocked yes)
			(layer "F.SilkS")
			(effects
				(font
					(size 0.7874 0.5842)
					(thickness 0.1524)
				)
				(justify left)
			)
		)
		(property "Value" "VAL*"
			(at -0.9398 3.70967 180)
			(unlocked yes)
			(layer "F.Fab")
			(hide yes)
			(effects
				(font
					(size 0.7874 0.5842)
					(thickness 0.1524)
				)
				(justify left)
			)
		)
		(property "Tolerance" "TOL*"
			(at -0.9906 5.00507 180)
			(unlocked yes)
			(layer "Cmts.User")
			(hide yes)
			(effects
				(font
					(size 0.7874 0.5842)
					(thickness 0.1524)
				)
				(justify left)
			)
		)
		(property "User Part Number" "PARTNUM*"
			(at -2.54 2.46507 180)
			(unlocked yes)
			(layer "Cmts.User")
			(hide yes)
			(effects
				(font
					(size 0.7874 0.5842)
					(thickness 0.1524)
				)
				(justify left)
			)
		)
		(property "Device Type" "FERRITEBEAD-G191-10100-01,120OA"
			(at -0.9906 1.22047 180)
			(unlocked yes)
			(layer "F.Fab")
			(hide yes)
			(effects
				(font
					(size 0.7874 0.5842)
					(thickness 0.1524)
				)
				(justify left)
			)
		)
		(duplicate_pad_numbers_are_jumpers no)
		(fp_line
			(start 1.3208 0.7112)
			(end -1.3208 0.7112)
			(stroke
				(width 0.1)
				(type default)
			)
			(layer "F.SilkS")
		)
		(fp_line
			(start 1.3208 -0.7112)
			(end 1.3208 0.7112)
			(stroke
				(width 0.1)
				(type default)
			)
			(layer "F.SilkS")
		)
		(fp_line
			(start -1.3208 0.7112)
			(end -1.3208 -0.7112)
			(stroke
				(width 0.1)
				(type default)
			)
			(layer "F.SilkS")
		)
		(fp_line
			(start -1.3208 -0.7112)
			(end 1.3208 -0.7112)
			(stroke
				(width 0.1)
				(type default)
			)
			(layer "F.SilkS")
		)
		(fp_rect
			(start -1.3208 0.7112)
			(end 1.3208 -0.7112)
			(stroke
				(width 0)
				(type default)
			)
			(fill no)
			(layer "F.CrtYd")
		)
		(fp_line
			(start 0.8128 0.4572)
			(end -0.8128 0.4572)
			(stroke
				(width 0.1)
				(type default)
			)
			(layer "F.Fab")
		)
		(fp_line
			(start 0.8128 -0.4572)
			(end 0.8128 0.4572)
			(stroke
				(width 0.1)
				(type default)
			)
			(layer "F.Fab")
		)
		(fp_line
			(start -0.8128 0.4572)
			(end -0.8128 -0.4572)
			(stroke
				(width 0.1)
				(type default)
			)
			(layer "F.Fab")
		)
		(fp_line
			(start -0.8128 -0.4572)
			(end 0.8128 -0.4572)
			(stroke
				(width 0.1)
				(type default)
			)
			(layer "F.Fab")
		)
		(pad "1" smd rect
			(at -0.6858 0 180)
			(size 0.762 0.8636)
			(layers "F.Cu" "F.Mask" "F.Paste")
			(net "XP1R8V_FPGA_VCCAUX")
		)
		(pad "2" smd rect
			(at 0.6858 0 180)
			(size 0.762 0.8636)
			(layers "F.Cu" "F.Mask" "F.Paste")
			(net "XP1R8V_FPGA")
		)
		(zone
			(layer "F.Cu")
			(hatch none 0.5)
			(connect_pads
				(clearance 0)
			)
			(min_thickness 0.25)
			(keepout
				(tracks not_allowed)
				(vias allowed)
				(pads allowed)
				(copperpour not_allowed)
				(footprints allowed)
			)
			(placement
				(enabled no)
				(sheetname "")
			)
			(fill
				(thermal_gap 0.5)
				(thermal_bridge_width 0.5)
				(island_removal_mode 0)
			)
			(polygon
				(pts
					(xy 92.9894 -56.4642) (xy 92.6846 -56.4642) (xy 92.6846 -55.5498) (xy 92.9894 -55.5498)
				)
			)
		)
		(zone
			(layer "F.Cu")
			(hatch none 0.5)
			(connect_pads
				(clearance 0)
			)
			(min_thickness 0.25)
			(keepout
				(tracks allowed)
				(vias not_allowed)
				(pads allowed)
				(copperpour not_allowed)
				(footprints allowed)
			)
			(placement
				(enabled no)
				(sheetname "")
			)
			(fill
				(thermal_gap 0.5)
				(thermal_bridge_width 0.5)
				(island_removal_mode 0)
			)
			(polygon
				(pts
					(xy 92.9894 -56.4642) (xy 92.6846 -56.4642) (xy 92.6846 -55.5498) (xy 92.9894 -55.5498)
				)
			)
		)
	)
	(footprint ""
		(layer "F.Cu")
		(at 90.9828 -73.0758 90)
		(property "Reference" "C199"
			(at 19.6342 -27.44343 90)
			(unlocked yes)
			(layer "F.SilkS")
			(effects
				(font
					(size 0.7874 0.5842)
					(thickness 0.1524)
				)
			)
		)
		(property "Value" "VAL*"
			(at 0.0762 2.067306 90)
			(unlocked yes)
			(layer "F.Fab")
			(hide yes)
			(effects
				(font
					(size 0.7874 0.5842)
					(thickness 0.1524)
				)
			)
		)
		(property "Device Type" "CAPACITOR-G105-0B104-CK,0.1UF,A"
			(at 0.0508 1.127506 90)
			(unlocked yes)
			(layer "F.Fab")
			(hide yes)
			(effects
				(font
					(size 0.7874 0.5842)
					(thickness 0.1524)
				)
			)
		)
		(property "User Part Number" "PARTNUM*"
			(at 0.1016 4.023106 90)
			(unlocked yes)
			(layer "Cmts.User")
			(hide yes)
			(effects
				(font
					(size 0.7874 0.5842)
					(thickness 0.1524)
				)
			)
		)
		(property "Tolerance" "TOL*"
			(at 0.0762 3.032506 90)
			(unlocked yes)
			(layer "Cmts.User")
			(hide yes)
			(effects
				(font
					(size 0.7874 0.5842)
					(thickness 0.1524)
				)
			)
		)
		(duplicate_pad_numbers_are_jumpers no)
		(fp_line
			(start 1.143 -0.5588)
			(end -1.143 -0.5588)
			(stroke
				(width 0.1)
				(type default)
			)
			(layer "F.SilkS")
		)
		(fp_line
			(start -1.143 -0.5588)
			(end -1.143 0.5588)
			(stroke
				(width 0.1)
				(type default)
			)
			(layer "F.SilkS")
		)
		(fp_line
			(start 1.143 0.5588)
			(end 1.143 -0.5588)
			(stroke
				(width 0.1)
				(type default)
			)
			(layer "F.SilkS")
		)
		(fp_line
			(start -1.143 0.5588)
			(end 1.143 0.5588)
			(stroke
				(width 0.1)
				(type default)
			)
			(layer "F.SilkS")
		)
		(fp_rect
			(start -1.143 -0.5588)
			(end 1.143 0.5588)
			(stroke
				(width 0)
				(type default)
			)
			(fill no)
			(layer "F.CrtYd")
		)
		(fp_line
			(start 0.508 -0.3048)
			(end -0.508 -0.3048)
			(stroke
				(width 0.1)
				(type default)
			)
			(layer "F.Fab")
		)
		(fp_line
			(start -0.508 -0.3048)
			(end -0.508 0.3048)
			(stroke
				(width 0.1)
				(type default)
			)
			(layer "F.Fab")
		)
		(fp_line
			(start 0.508 0.3048)
			(end 0.508 -0.3048)
			(stroke
				(width 0.1)
				(type default)
			)
			(layer "F.Fab")
		)
		(fp_line
			(start -0.508 0.3048)
			(end 0.508 0.3048)
			(stroke
				(width 0.1)
				(type default)
			)
			(layer "F.Fab")
		)
		(pad "1" smd rect
			(at -0.5334 0 90)
			(size 0.7112 0.6096)
			(layers "F.Cu" "F.Mask" "F.Paste")
			(net "XP3R3V_FPGA")
		)
		(pad "2" smd rect
			(at 0.5334 0 90)
			(size 0.7112 0.6096)
			(layers "F.Cu" "F.Mask" "F.Paste")
			(net "SG")
		)
		(zone
			(layer "F.Cu")
			(hatch none 0.5)
			(connect_pads
				(clearance 0)
			)
			(min_thickness 0.25)
			(keepout
				(tracks allowed)
				(vias not_allowed)
				(pads allowed)
				(copperpour not_allowed)
				(footprints allowed)
			)
			(placement
				(enabled no)
				(sheetname "")
			)
			(fill
				(thermal_gap 0.5)
				(thermal_bridge_width 0.5)
				(island_removal_mode 0)
			)
			(polygon
				(pts
					(xy 90.678 -72.9996) (xy 91.2876 -72.9996) (xy 91.2876 -73.152) (xy 90.678 -73.152)
				)
			)
		)
	)
	(footprint ""
		(layer "F.Cu")
		(at 1.500124 -39.099998 90)
		(property "Reference" "DS14"
			(at 2.770632 1.293876 0)
			(unlocked yes)
			(layer "F.SilkS")
			(effects
				(font
					(size 0.7874 0.5842)
					(thickness 0.1524)
				)
			)
		)
		(property "Value" ""
			(at 0 0 90)
			(layer "F.Fab")
			(effects
				(font
					(size 1.27 1.27)
				)
			)
		)
		(property "User Part Number" "PARTNUM*"
			(at 0.015494 4.486402 90)
			(unlocked yes)
			(layer "Cmts.User")
			(hide yes)
			(effects
				(font
					(size 0.7874 0.5842)
					(thickness 0.1524)
				)
			)
		)
		(property "Device Type" "LED_4P_V14-G170-10189-01"
			(at 0.015494 3.292602 90)
			(unlocked yes)
			(layer "F.Fab")
			(hide yes)
			(effects
				(font
					(size 0.7874 0.5842)
					(thickness 0.1524)
				)
			)
		)
		(duplicate_pad_numbers_are_jumpers no)
		(fp_line
			(start 1.378966 -0.829056)
			(end -1.378966 -0.829056)
			(stroke
				(width 0.1)
				(type default)
			)
			(layer "F.SilkS")
		)
		(fp_line
			(start -1.378966 -0.829056)
			(end -1.378966 -0.452628)
			(stroke
				(width 0.1)
				(type default)
			)
			(layer "F.SilkS")
		)
		(fp_line
			(start 1.998218 -0.452628)
			(end 1.378966 -0.452628)
			(stroke
				(width 0.1)
				(type default)
			)
			(layer "F.SilkS")
		)
		(fp_line
			(start 1.378966 -0.452628)
			(end 1.378966 -0.829056)
			(stroke
				(width 0.1)
				(type default)
			)
			(layer "F.SilkS")
		)
		(fp_line
			(start -1.378966 -0.452628)
			(end -1.998218 -0.452628)
			(stroke
				(width 0.1)
				(type default)
			)
			(layer "F.SilkS")
		)
		(fp_line
			(start -1.998218 -0.452628)
			(end -1.998218 1.103884)
			(stroke
				(width 0.1)
				(type default)
			)
			(layer "F.SilkS")
		)
		(fp_line
			(start 1.998218 1.103884)
			(end 1.998218 -0.452628)
			(stroke
				(width 0.1)
				(type default)
			)
			(layer "F.SilkS")
		)
		(fp_line
			(start -1.998218 1.103884)
			(end 1.998218 1.103884)
			(stroke
				(width 0.1)
				(type default)
			)
			(layer "F.SilkS")
		)
		(fp_poly
			(pts
				(xy 0.918464 -1.698498) (xy 1.223264 -1.46939) (xy 0.994664 -1.46939) (xy 0.994664 -1.24079) (xy 0.842264 -1.24079)
				(xy 0.842264 -1.46939) (xy 0.613664 -1.46939)
			)
			(stroke
				(width 0)
				(type default)
			)
			(fill yes)
			(layer "F.SilkS")
		)
		(fp_poly
			(pts
				(xy -0.73406 -1.677416) (xy -0.42926 -1.448308) (xy -0.65786 -1.448308) (xy -0.65786 -1.219708)
				(xy -0.81026 -1.219708) (xy -0.81026 -1.448308) (xy -1.03886 -1.448308)
			)
			(stroke
				(width 0)
				(type default)
			)
			(fill yes)
			(layer "F.SilkS")
		)
		(fp_poly
			(pts
				(xy -2.252218 1.357884) (xy -2.252218 -0.706628) (xy -1.632966 -0.706628) (xy -1.632966 -1.083056)
				(xy 1.632966 -1.083056) (xy 1.632966 -0.706628) (xy 2.252218 -0.706628) (xy 2.252218 1.357884)
			)
			(stroke
				(width 0)
				(type default)
			)
			(fill no)
			(layer "F.CrtYd")
		)
		(fp_line
			(start 1.124966 -0.575056)
			(end -1.124966 -0.575056)
			(stroke
				(width 0.1)
				(type default)
			)
			(layer "F.Fab")
		)
		(fp_line
			(start -1.124966 -0.575056)
			(end -1.124966 -0.075184)
			(stroke
				(width 0.1)
				(type default)
			)
			(layer "F.Fab")
		)
		(fp_line
			(start 1.325118 -0.075184)
			(end 1.124966 -0.075184)
			(stroke
				(width 0.1)
				(type default)
			)
			(layer "F.Fab")
		)
		(fp_line
			(start 1.124966 -0.075184)
			(end 1.124966 -0.575056)
			(stroke
				(width 0.1)
				(type default)
			)
			(layer "F.Fab")
		)
		(fp_line
			(start -1.124966 -0.075184)
			(end -1.325118 -0.075184)
			(stroke
				(width 0.1)
				(type default)
			)
			(layer "F.Fab")
		)
		(fp_line
			(start -1.325118 -0.075184)
			(end -1.325118 0.574802)
			(stroke
				(width 0.1)
				(type default)
			)
			(layer "F.Fab")
		)
		(fp_line
			(start 1.325118 0.574802)
			(end 1.325118 -0.075184)
			(stroke
				(width 0.1)
				(type default)
			)
			(layer "F.Fab")
		)
		(fp_line
			(start -1.325118 0.574802)
			(end 1.325118 0.574802)
			(stroke
				(width 0.1)
				(type default)
			)
			(layer "F.Fab")
		)
		(fp_poly
			(pts
				(xy 0.918464 -1.698498) (xy 1.223264 -1.46939) (xy 0.994664 -1.46939) (xy 0.994664 -1.24079) (xy 0.842264 -1.24079)
				(xy 0.842264 -1.46939) (xy 0.613664 -1.46939)
			)
			(stroke
				(width 0)
				(type default)
			)
			(fill yes)
			(layer "F.Fab")
		)
		(fp_poly
			(pts
				(xy -0.73406 -1.677416) (xy -0.42926 -1.448308) (xy -0.65786 -1.448308) (xy -0.65786 -1.219708)
				(xy -0.81026 -1.219708) (xy -0.81026 -1.448308) (xy -1.03886 -1.448308)
			)
			(stroke
				(width 0)
				(type default)
			)
			(fill yes)
			(layer "F.Fab")
		)
		(fp_text user "4"
			(at 2.778252 -0.611124 0)
			(unlocked yes)
			(layer "F.SilkS")
			(effects
				(font
					(size 0.635 0.4064)
					(thickness 0.1524)
				)
			)
		)
		(fp_text user "1"
			(at -2.37617 0.376936 90)
			(unlocked yes)
			(layer "F.SilkS")
			(effects
				(font
					(size 0.7874 0.5842)
					(thickness 0.1524)
				)
			)
		)
		(fp_text user "2"
			(at -1.158748 1.420876 0)
			(unlocked yes)
			(layer "F.SilkS")
			(effects
				(font
					(size 0.635 0.4064)
					(thickness 0.1524)
				)
			)
		)
		(fp_text user "3"
			(at 1.305052 1.547876 0)
			(unlocked yes)
			(layer "F.SilkS")
			(effects
				(font
					(size 0.635 0.4064)
					(thickness 0.1524)
				)
			)
		)
		(fp_text user "4"
			(at 1.92532 1.166876 0)
			(unlocked yes)
			(layer "F.Fab")
			(effects
				(font
					(size 0.7874 0.5842)
					(thickness 0.1524)
				)
			)
		)
		(fp_text user "3"
			(at 0.738632 1.166876 0)
			(unlocked yes)
			(layer "F.Fab")
			(effects
				(font
					(size 0.7874 0.5842)
					(thickness 0.1524)
				)
			)
		)
		(fp_text user "2"
			(at -0.531368 1.293876 0)
			(unlocked yes)
			(layer "F.Fab")
			(effects
				(font
					(size 0.7874 0.5842)
					(thickness 0.1524)
				)
			)
		)
		(fp_text user "1"
			(at -1.674368 1.293876 0)
			(unlocked yes)
			(layer "F.Fab")
			(effects
				(font
					(size 0.7874 0.5842)
					(thickness 0.1524)
				)
			)
		)
		(pad "1" smd rect
			(at -1.325118 0.245872 90)
			(size 0.8382 0.889)
			(layers "F.Cu" "F.Mask" "F.Paste")
			(net "UNNAMED_14_LED4PV14_I265_1")
		)
		(pad "2" smd rect
			(at -0.424942 0.595884 90)
			(size 0.4572 0.508)
			(layers "F.Cu" "F.Mask" "F.Paste")
			(net "XP3R3V_FPGA")
		)
		(pad "3" smd rect
			(at 0.424942 0.595884 90)
			(size 0.4572 0.508)
			(layers "F.Cu" "F.Mask" "F.Paste")
			(net "UNNAMED_14_LED4PV14_I265_3")
		)
		(pad "4" smd rect
			(at 1.325118 0.245872 90)
			(size 0.8382 0.889)
			(layers "F.Cu" "F.Mask" "F.Paste")
			(net "UNNAMED_14_LED4PV14_I265_4")
		)
	)
)
